# S9S_MB_2U (Grand Teton) — schematic netlist excerpt (pin names and nets, part order shuffled) for the footprints in the layout excerpt that follows; sources: Cadence DE-HDL packaged netlist, KiCad conversion of 03242023_DA0F0TMBIJ0_F0T_Motherboard_J_brd_V01_OCP.brd

R553  Q_RES  0 5% CHIP  pkg 0402LF  page 209 : A = CLK_100M_CK440_PCH_EXTCLK_R_DP ; B = CLK_100M_CK440_PCH_EXTCLK_DP
PC2197  Q_CAP  39PF 50V 5% EMPTY  pkg C0402  page 193 : A = P3V3_E1S_MODE_0 ; B = GND

(kicad_pcb
	(version 20260206)
	(generator "pcbnew")
	(generator_version "10.0")
	(general
		(thickness 1.6)
		(legacy_teardrops no)
	)
	(paper "A4")
	(title_block
		(title "03242023_DA0F0TMBIJ0_F0T_Motherboard_J_brd_V01_OCP.brd")
		(comment 1 "Grand Teton / footprints 2776-2777 of 6105")
	)
	(layers
		(0 "F.Cu" signal "TOP")
		(4 "In1.Cu" signal "GND")
		(6 "In2.Cu" signal "IN1")
		(8 "In3.Cu" signal "GND1")
		(10 "In4.Cu" signal "IN2")
		(12 "In5.Cu" signal "GND2")
		(14 "In6.Cu" signal "IN3")
		(16 "In7.Cu" signal "GND3")
		(18 "In8.Cu" signal "VCC")
		(20 "In9.Cu" signal "VCC1")
		(22 "In10.Cu" signal "GND4")
		(24 "In11.Cu" signal "IN4")
		(26 "In12.Cu" signal "GND5")
		(28 "In13.Cu" signal "IN5")
		(30 "In14.Cu" signal "GND6")
		(32 "In15.Cu" signal "IN6")
		(34 "In16.Cu" signal "GND7")
		(2 "B.Cu" signal "BOTTOM")
		(9 "F.Adhes" user "F.Adhesive")
		(11 "B.Adhes" user "B.Adhesive")
		(13 "F.Paste" user "Package Geometry/Pastemask Top")
		(15 "B.Paste" user "Package Geometry/Pastemask Bottom")
		(5 "F.SilkS" user "Ref Des/Silkscreen Top")
		(7 "B.SilkS" user "Ref Des/Silkscreen Bottom")
		(1 "F.Mask" user "Board Geometry/Soldermask Top")
		(3 "B.Mask" user "Board Geometry/Soldermask Bottom")
		(17 "Dwgs.User" user "User.Drawings")
		(19 "Cmts.User" user "User.Comments")
		(21 "Eco1.User" user "User.Eco1")
		(23 "Eco2.User" user "User.Eco2")
		(25 "Edge.Cuts" user "Board Geometry/Outline")
		(27 "Margin" user)
		(31 "F.CrtYd" user "Package Geometry/Place Bound Top")
		(29 "B.CrtYd" user "Package Geometry/Place Bound Bottom")
		(35 "F.Fab" user "Ref Des/Assembly Top")
		(33 "B.Fab" user "Ref Des/Assembly Bottom")
	)
	(footprint ""
		(layer "F.Cu")
		(at 257.176524 -108.154216 90)
		(property "Reference" "R553"
			(at 0 0 90)
			(layer "F.SilkS")
			(hide yes)
			(effects
				(font
					(size 1.27 1.27)
				)
			)
		)
		(property "Value" ""
			(at 0 0 90)
			(layer "F.Fab")
			(effects
				(font
					(size 1.27 1.27)
				)
			)
		)
		(duplicate_pad_numbers_are_jumpers no)
		(fp_line
			(start 0.7874 -0.4064)
			(end 0.7874 0.4064)
			(stroke
				(width 0.1524)
				(type default)
			)
			(layer "F.SilkS")
		)
		(fp_line
			(start -0.7874 -0.4064)
			(end 0.7874 -0.4064)
			(stroke
				(width 0.1524)
				(type default)
			)
			(layer "F.SilkS")
		)
		(fp_line
			(start 0.7874 0.4064)
			(end -0.7874 0.4064)
			(stroke
				(width 0.1524)
				(type default)
			)
			(layer "F.SilkS")
		)
		(fp_line
			(start -0.7874 0.4064)
			(end -0.7874 -0.4064)
			(stroke
				(width 0.1524)
				(type default)
			)
			(layer "F.SilkS")
		)
		(fp_line
			(start -0.12065 -0.305054)
			(end -0.12065 -0.2794)
			(stroke
				(width 0.1)
				(type default)
			)
			(layer "F.Fab")
		)
		(fp_line
			(start -0.67945 -0.305054)
			(end -0.12065 -0.305054)
			(stroke
				(width 0.1)
				(type default)
			)
			(layer "F.Fab")
		)
		(fp_line
			(start 0.67945 -0.3048)
			(end 0.67945 0.3048)
			(stroke
				(width 0.1)
				(type default)
			)
			(layer "F.Fab")
		)
		(fp_line
			(start 0.12065 -0.3048)
			(end 0.67945 -0.3048)
			(stroke
				(width 0.1)
				(type default)
			)
			(layer "F.Fab")
		)
		(fp_line
			(start 0.12065 -0.2794)
			(end 0.12065 -0.3048)
			(stroke
				(width 0.1)
				(type default)
			)
			(layer "F.Fab")
		)
		(fp_line
			(start -0.12065 -0.2794)
			(end 0.12065 -0.2794)
			(stroke
				(width 0.1)
				(type default)
			)
			(layer "F.Fab")
		)
		(fp_line
			(start 0.120396 0.2794)
			(end -0.12065 0.2794)
			(stroke
				(width 0.1)
				(type default)
			)
			(layer "F.Fab")
		)
		(fp_line
			(start -0.12065 0.2794)
			(end -0.12065 0.3048)
			(stroke
				(width 0.1)
				(type default)
			)
			(layer "F.Fab")
		)
		(fp_line
			(start 0.67945 0.3048)
			(end 0.120396 0.3048)
			(stroke
				(width 0.1)
				(type default)
			)
			(layer "F.Fab")
		)
		(fp_line
			(start 0.120396 0.3048)
			(end 0.120396 0.2794)
			(stroke
				(width 0.1)
				(type default)
			)
			(layer "F.Fab")
		)
		(fp_line
			(start -0.12065 0.3048)
			(end -0.67945 0.3048)
			(stroke
				(width 0.1)
				(type default)
			)
			(layer "F.Fab")
		)
		(fp_line
			(start -0.67945 0.3048)
			(end -0.67945 -0.305054)
			(stroke
				(width 0.1)
				(type default)
			)
			(layer "F.Fab")
		)
		(pad "1" smd circle
			(at -0.40005 0 90)
			(size 0 0)
			(layers "F.Cu" "F.Mask" "F.Paste")
			(net "CLK_100M_CK440_PCH_EXTCLK_R_DP")
		)
		(pad "2" smd circle
			(at 0.40005 0 90)
			(size 0 0)
			(layers "F.Cu" "F.Mask" "F.Paste")
			(net "CLK_100M_CK440_PCH_EXTCLK_DP")
		)
	)
	(footprint ""
		(layer "F.Cu")
		(at 190.41364 -68.407788 180)
		(property "Reference" "PC2197"
			(at 0 0 180)
			(layer "F.SilkS")
			(hide yes)
			(effects
				(font
					(size 1.27 1.27)
				)
			)
		)
		(property "Value" ""
			(at 0 0 180)
			(layer "F.Fab")
			(effects
				(font
					(size 1.27 1.27)
				)
			)
		)
		(duplicate_pad_numbers_are_jumpers no)
		(fp_line
			(start 0.7874 0.4064)
			(end -0.7874 0.4064)
			(stroke
				(width 0.1524)
				(type default)
			)
			(layer "F.SilkS")
		)
		(fp_line
			(start 0.7874 -0.4064)
			(end 0.7874 0.4064)
			(stroke
				(width 0.1524)
				(type default)
			)
			(layer "F.SilkS")
		)
		(fp_line
			(start -0.7874 0.4064)
			(end -0.7874 -0.4064)
			(stroke
				(width 0.1524)
				(type default)
			)
			(layer "F.SilkS")
		)
		(fp_line
			(start -0.7874 -0.4064)
			(end 0.7874 -0.4064)
			(stroke
				(width 0.1524)
				(type default)
			)
			(layer "F.SilkS")
		)
		(fp_line
			(start 0.67945 0.3048)
			(end 0.120396 0.3048)
			(stroke
				(width 0.1)
				(type default)
			)
			(layer "F.Fab")
		)
		(fp_line
			(start 0.67945 -0.3048)
			(end 0.67945 0.3048)
			(stroke
				(width 0.1)
				(type default)
			)
			(layer "F.Fab")
		)
		(fp_line
			(start 0.12065 -0.2794)
			(end 0.12065 -0.3048)
			(stroke
				(width 0.1)
				(type default)
			)
			(layer "F.Fab")
		)
		(fp_line
			(start 0.12065 -0.3048)
			(end 0.67945 -0.3048)
			(stroke
				(width 0.1)
				(type default)
			)
			(layer "F.Fab")
		)
		(fp_line
			(start 0.120396 0.3048)
			(end 0.120396 0.2794)
			(stroke
				(width 0.1)
				(type default)
			)
			(layer "F.Fab")
		)
		(fp_line
			(start 0.120396 0.2794)
			(end -0.12065 0.2794)
			(stroke
				(width 0.1)
				(type default)
			)
			(layer "F.Fab")
		)
		(fp_line
			(start -0.12065 0.3048)
			(end -0.67945 0.3048)
			(stroke
				(width 0.1)
				(type default)
			)
			(layer "F.Fab")
		)
		(fp_line
			(start -0.12065 0.2794)
			(end -0.12065 0.3048)
			(stroke
				(width 0.1)
				(type default)
			)
			(layer "F.Fab")
		)
		(fp_line
			(start -0.12065 -0.2794)
			(end 0.12065 -0.2794)
			(stroke
				(width 0.1)
				(type default)
			)
			(layer "F.Fab")
		)
		(fp_line
			(start -0.12065 -0.305054)
			(end -0.12065 -0.2794)
			(stroke
				(width 0.1)
				(type default)
			)
			(layer "F.Fab")
		)
		(fp_line
			(start -0.67945 0.3048)
			(end -0.67945 -0.305054)
			(stroke
				(width 0.1)
				(type default)
			)
			(layer "F.Fab")
		)
		(fp_line
			(start -0.67945 -0.305054)
			(end -0.12065 -0.305054)
			(stroke
				(width 0.1)
				(type default)
			)
			(layer "F.Fab")
		)
		(pad "1" smd circle
			(at -0.40005 0 180)
			(size 0 0)
			(layers "F.Cu" "F.Mask" "F.Paste")
			(net "P3V3_E1S_MODE_0")
		)
		(pad "2" smd circle
			(at 0.40005 0 180)
			(size 0 0)
			(layers "F.Cu" "F.Mask" "F.Paste")
			(net "GND")
		)
	)
)
